(kicad_pcb
	(version 20260206)
	(generator "pcbnew")
	(generator_version "10.0")
	(general
		(thickness 1.6)
		(legacy_teardrops no)
	)
	(paper "A4")
	(title_block
		(title "Bryce Canyon_F.DPB_16315-1-OCP.brd")
		(comment 1 "Bryce Canyon / footprints 398-401 of 2223")
	)
	(layers
		(0 "F.Cu" signal "TOP")
		(4 "In1.Cu" signal "L2GND")
		(6 "In2.Cu" signal "L3")
		(8 "In3.Cu" signal "L4GND")
		(10 "In4.Cu" signal "L5")
		(12 "In5.Cu" signal "L6VCC")
		(14 "In6.Cu" signal "L7VCC")
		(16 "In7.Cu" signal "L8")
		(18 "In8.Cu" signal "L9GND")
		(20 "In9.Cu" signal "L10")
		(22 "In10.Cu" signal "L11GND")
		(2 "B.Cu" signal "BOTTOM")
		(9 "F.Adhes" user "F.Adhesive")
		(11 "B.Adhes" user "B.Adhesive")
		(13 "F.Paste" user "Package Geometry/Pastemask Top")
		(15 "B.Paste" user "Package Geometry/Pastemask Bottom")
		(5 "F.SilkS" user "Ref Des/Silkscreen Top")
		(7 "B.SilkS" user "Ref Des/Silkscreen Bottom")
		(1 "F.Mask" user "Board Geometry/Soldermask Top")
		(3 "B.Mask" user "Board Geometry/Soldermask Bottom")
		(17 "Dwgs.User" user "User.Drawings")
		(19 "Cmts.User" user "User.Comments")
		(21 "Eco1.User" user "User.Eco1")
		(23 "Eco2.User" user "User.Eco2")
		(25 "Edge.Cuts" user "Board Geometry/Outline")
		(27 "Margin" user)
		(31 "F.CrtYd" user "Package Geometry/Place Bound Top")
		(29 "B.CrtYd" user "Package Geometry/Place Bound Bottom")
		(35 "F.Fab" user "Ref Des/Assembly Top")
		(33 "B.Fab" user "Ref Des/Assembly Bottom")
	)
	(footprint ""
		(layer "F.Cu")
		(at 48.374046 -53.101494 -90)
		(property "Reference" "C373"
			(at 0 0 270)
			(layer "F.SilkS")
			(hide yes)
			(effects
				(font
					(size 1.27 1.27)
				)
			)
		)
		(property "Value" "SCD033U25V2KX-GP"
			(at 1.1811 -2.7051 270)
			(unlocked yes)
			(layer "F.Fab")
			(hide yes)
			(effects
				(font
					(size 1.016 1.016)
					(thickness 0.1524)
				)
			)
		)
		(property "Device Type" "C402H22"
			(at 1.1811 -4.2291 270)
			(unlocked yes)
			(layer "F.Fab")
			(hide yes)
			(effects
				(font
					(size 1.016 1.016)
					(thickness 0.1524)
				)
			)
		)
		(duplicate_pad_numbers_are_jumpers no)
		(fp_rect
			(start -0.4318 0.9525)
			(end 0.4318 -0.9525)
			(stroke
				(width 0)
				(type default)
			)
			(fill no)
			(layer "F.CrtYd")
		)
		(fp_rect
			(start -0.4318 0.9525)
			(end 0.4318 -0.9525)
			(stroke
				(width 0)
				(type default)
			)
			(fill no)
			(layer "F.Fab")
		)
		(pad "1" smd custom
			(at 0 -0.4445 270)
			(size 0.1524 0.1524)
			(layers "F.Cu" "F.Mask" "F.Paste")
			(net "SW_HDD_P25")
			(options
				(clearance outline)
				(anchor circle)
			)
			(primitives
				(gr_poly
					(pts
						(arc
							(start 0.3048 -0.2032)
							(mid 0.275042 -0.275042)
							(end 0.2032 -0.3048)
						)
						(arc
							(start -0.2032 -0.3048)
							(mid -0.275042 -0.275042)
							(end -0.3048 -0.2032)
						)
						(arc
							(start -0.3048 0.2032)
							(mid -0.275042 0.275042)
							(end -0.2032 0.3048)
						)
						(arc
							(start 0.2032 0.3048)
							(mid 0.275042 0.275042)
							(end 0.3048 0.2032)
						)
					)
					(width 0)
					(fill yes)
				)
			)
		)
		(pad "2" smd custom
			(at 0 0.4445 270)
			(size 0.1524 0.1524)
			(layers "F.Cu" "F.Mask" "F.Paste")
			(net "GND")
			(options
				(clearance outline)
				(anchor circle)
			)
			(primitives
				(gr_poly
					(pts
						(arc
							(start 0.3048 -0.2032)
							(mid 0.275042 -0.275042)
							(end 0.2032 -0.3048)
						)
						(arc
							(start -0.2032 -0.3048)
							(mid -0.275042 -0.275042)
							(end -0.3048 -0.2032)
						)
						(arc
							(start -0.3048 0.2032)
							(mid -0.275042 0.275042)
							(end -0.2032 0.3048)
						)
						(arc
							(start 0.2032 0.3048)
							(mid 0.275042 0.275042)
							(end 0.3048 0.2032)
						)
					)
					(width 0)
					(fill yes)
				)
			)
		)
	)
	(footprint ""
		(layer "F.Cu")
		(at 166.324788 -9.19988)
		(property "Reference" ""
			(at 0 0 0)
			(layer "F.SilkS")
			(hide yes)
			(effects
				(font
					(size 1.27 1.27)
				)
			)
		)
		(property "Value" "*"
			(at -6.1214 1.4351 0)
			(unlocked yes)
			(layer "F.Fab")
			(hide yes)
			(effects
				(font
					(size 1.016 1.016)
					(thickness 0.1524)
				)
			)
		)
		(duplicate_pad_numbers_are_jumpers no)
		(fp_poly
			(pts
				(arc
					(start 5.0673 0)
					(mid -5.0673 0)
					(end 5.0673 0)
				)
			)
			(stroke
				(width 0)
				(type default)
			)
			(fill no)
			(layer "B.CrtYd")
		)
		(fp_poly
			(pts
				(arc
					(start 5.0673 0)
					(mid -5.0673 0)
					(end 5.0673 0)
				)
			)
			(stroke
				(width 0)
				(type default)
			)
			(fill no)
			(layer "F.CrtYd")
		)
		(fp_poly
			(pts
				(arc
					(start 5.0673 0)
					(mid -5.0673 0)
					(end 5.0673 0)
				)
			)
			(stroke
				(width 0)
				(type default)
			)
			(fill no)
			(layer "B.Fab")
		)
		(fp_poly
			(pts
				(arc
					(start 5.0673 0)
					(mid -5.0673 0)
					(end 5.0673 0)
				)
			)
			(stroke
				(width 0)
				(type default)
			)
			(fill no)
			(layer "F.Fab")
		)
		(pad "1" thru_hole circle
			(at 0 0)
			(size 9.525 9.525)
			(drill 5.715)
			(layers "*.Cu" "*.Mask")
			(remove_unused_layers no)
			(net "Net_30")
			(clearance -1.397)
			(thermal_gap 0.3048)
			(padstack
				(mode front_inner_back)
				(layer "Inner"
					(shape circle)
					(size 6.1214 6.1214)
					(clearance 0.3048)
				)
				(layer "B.Cu"
					(shape circle)
					(size 9.525 9.525)
					(clearance -1.397)
				)
			)
		)
		(zone
			(layers "F.Cu" "B.Cu" "In1.Cu" "In2.Cu" "In3.Cu" "In4.Cu" "In5.Cu" "In6.Cu"
				"In7.Cu" "In8.Cu" "In9.Cu" "In10.Cu"
			)
			(hatch none 0.5)
			(connect_pads
				(clearance 0)
			)
			(min_thickness 0.25)
			(keepout
				(tracks not_allowed)
				(vias allowed)
				(pads allowed)
				(copperpour not_allowed)
				(footprints allowed)
			)
			(placement
				(enabled no)
				(sheetname "")
			)
			(fill
				(thermal_gap 0.5)
				(thermal_bridge_width 0.5)
				(island_removal_mode 0)
			)
			(polygon
				(pts
					(arc
						(start 171.087288 -9.19988)
						(mid 161.562288 -9.19988)
						(end 171.087288 -9.19988)
					)
				)
			)
		)
	)
	(footprint ""
		(layer "F.Cu")
		(at 479.384614 -159.219392 -90)
		(property "Reference" "C337"
			(at 0 0 270)
			(layer "F.SilkS")
			(hide yes)
			(effects
				(font
					(size 1.27 1.27)
				)
			)
		)
		(property "Value" "SCD01U16V1KX-GP"
			(at -2.8321 -1.7399 270)
			(unlocked yes)
			(layer "F.Fab")
			(hide yes)
			(effects
				(font
					(size 1.016 1.016)
					(thickness 0.1524)
				)
			)
		)
		(property "Device Type" "C0201H13"
			(at -2.8321 -3.2639 270)
			(unlocked yes)
			(layer "F.Fab")
			(hide yes)
			(effects
				(font
					(size 1.016 1.016)
					(thickness 0.1524)
				)
			)
		)
		(duplicate_pad_numbers_are_jumpers no)
		(fp_rect
			(start -0.2794 0.6477)
			(end 0.2794 -0.6477)
			(stroke
				(width 0)
				(type default)
			)
			(fill no)
			(layer "F.CrtYd")
		)
		(fp_rect
			(start -0.2794 0.6477)
			(end 0.2794 -0.6477)
			(stroke
				(width 0)
				(type default)
			)
			(fill no)
			(layer "F.Fab")
		)
		(pad "1" smd custom
			(at 0 -0.2794 270)
			(size 0.0762 0.0762)
			(layers "F.Cu" "F.Mask" "F.Paste")
			(net "SAS_HDD_RX_N23")
			(options
				(clearance outline)
				(anchor circle)
			)
			(primitives
				(gr_poly
					(pts
						(arc
							(start 0.1524 -0.127)
							(mid 0.137521 -0.162921)
							(end 0.1016 -0.1778)
						)
						(arc
							(start -0.1016 -0.1778)
							(mid -0.137521 -0.162921)
							(end -0.1524 -0.127)
						)
						(arc
							(start -0.1524 0.127)
							(mid -0.137521 0.162921)
							(end -0.1016 0.1778)
						)
						(arc
							(start 0.1016 0.1778)
							(mid 0.137521 0.162921)
							(end 0.1524 0.127)
						)
					)
					(width 0)
					(fill yes)
				)
			)
		)
		(pad "2" smd custom
			(at 0 0.2794 270)
			(size 0.0762 0.0762)
			(layers "F.Cu" "F.Mask" "F.Paste")
			(net "PHY_SCC_A_TO_DRV_A_23_DN")
			(options
				(clearance outline)
				(anchor circle)
			)
			(primitives
				(gr_poly
					(pts
						(arc
							(start 0.1524 -0.127)
							(mid 0.137521 -0.162921)
							(end 0.1016 -0.1778)
						)
						(arc
							(start -0.1016 -0.1778)
							(mid -0.137521 -0.162921)
							(end -0.1524 -0.127)
						)
						(arc
							(start -0.1524 0.127)
							(mid -0.137521 0.162921)
							(end -0.1016 0.1778)
						)
						(arc
							(start 0.1016 0.1778)
							(mid 0.137521 0.162921)
							(end 0.1524 0.127)
						)
					)
					(width 0)
					(fill yes)
				)
			)
		)
	)
	(footprint ""
		(layer "F.Cu")
		(at 243.332 -395.9098 180)
		(property "Reference" "C589"
			(at 0 0 180)
			(layer "F.SilkS")
			(hide yes)
			(effects
				(font
					(size 1.27 1.27)
				)
			)
		)
		(property "Value" "SCD1U25V2KX-2-GP"
			(at 1.1811 -2.7051 180)
			(unlocked yes)
			(layer "F.Fab")
			(hide yes)
			(effects
				(font
					(size 1.016 1.016)
					(thickness 0.1524)
				)
			)
		)
		(property "Device Type" "C402H22"
			(at 1.1811 -4.2291 180)
			(unlocked yes)
			(layer "F.Fab")
			(hide yes)
			(effects
				(font
					(size 1.016 1.016)
					(thickness 0.1524)
				)
			)
		)
		(duplicate_pad_numbers_are_jumpers no)
		(fp_rect
			(start -0.4318 0.9525)
			(end 0.4318 -0.9525)
			(stroke
				(width 0)
				(type default)
			)
			(fill no)
			(layer "F.CrtYd")
		)
		(fp_rect
			(start -0.4318 0.9525)
			(end 0.4318 -0.9525)
			(stroke
				(width 0)
				(type default)
			)
			(fill no)
			(layer "F.Fab")
		)
		(pad "1" smd custom
			(at 0 -0.4445 180)
			(size 0.1524 0.1524)
			(layers "F.Cu" "F.Mask" "F.Paste")
			(net "MB3_PSET_R")
			(options
				(clearance outline)
				(anchor circle)
			)
			(primitives
				(gr_poly
					(pts
						(arc
							(start 0.3048 -0.2032)
							(mid 0.275042 -0.275042)
							(end 0.2032 -0.3048)
						)
						(arc
							(start -0.2032 -0.3048)
							(mid -0.275042 -0.275042)
							(end -0.3048 -0.2032)
						)
						(arc
							(start -0.3048 0.2032)
							(mid -0.275042 0.275042)
							(end -0.2032 0.3048)
						)
						(arc
							(start 0.2032 0.3048)
							(mid 0.275042 0.275042)
							(end 0.3048 0.2032)
						)
					)
					(width 0)
					(fill yes)
				)
			)
		)
		(pad "2" smd custom
			(at 0 0.4445 180)
			(size 0.1524 0.1524)
			(layers "F.Cu" "F.Mask" "F.Paste")
			(net "AGND_CURRENT_DPB")
			(options
				(clearance outline)
				(anchor circle)
			)
			(primitives
				(gr_poly
					(pts
						(arc
							(start 0.3048 -0.2032)
							(mid 0.275042 -0.275042)
							(end 0.2032 -0.3048)
						)
						(arc
							(start -0.2032 -0.3048)
							(mid -0.275042 -0.275042)
							(end -0.3048 -0.2032)
						)
						(arc
							(start -0.3048 0.2032)
							(mid -0.275042 0.275042)
							(end -0.2032 0.3048)
						)
						(arc
							(start 0.2032 0.3048)
							(mid 0.275042 0.275042)
							(end 0.3048 0.2032)
						)
					)
					(width 0)
					(fill yes)
				)
			)
		)
	)
)
